#ISCELL
  mstr_misc dns *
  *
#ISCELL
  pure_quanta quanta_title_block_c *
  *
#ISCELL
  pure_quanta_power cad_note *
  *
#ISCELL
  pure_quanta_power p1v0 *
  page398_i1
#ISCELL
  pure_quanta_power universal_gnd *
  page398_i10
#CELL
  pure_quanta q_cap *
  page398_i100
#CELL
  pure_quanta q_cap *
  page398_i101
#CELL
  pure_quanta q_cap *
  page398_i102
#CELL
  pure_quanta q_capp *
  page398_i103
#CELL
  pure_quanta q_capp *
  page398_i104
#CELL
  pure_quanta q_cap *
  page398_i105
#CELL
  pure_quanta q_cap *
  page398_i12
#CELL
  pure_quanta q_cap *
  page398_i14
#CELL
  pure_quanta q_cap *
  page398_i15
#ISCELL
  pure_quanta_power universal_gnd *
  page398_i17
#CELL
  pure_quanta q_cap *
  page398_i18
#CELL
  pure_quanta q_cap *
  page398_i19
#CELL
  pure_quanta q_cap *
  page398_i20
#CELL
  pure_quanta q_cap *
  page398_i21
#CELL
  pure_quanta q_inductor *
  page398_i22
#CELL
  pure_quanta q_cap *
  page398_i23
#CELL
  pure_quanta q_cap *
  page398_i24
#CELL
  pure_quanta q_cap *
  page398_i25
#CELL
  pure_quanta q_cap *
  page398_i26
#CELL
  pure_quanta q_cap *
  page398_i27
#ISCELL
  pure_quanta_power universal_gnd *
  page398_i28
#ISCELL
  pure_quanta_power p1v0 *
  page398_i29
#ISCELL
  pure_quanta_power p1v0 *
  page398_i3
#CELL
  pure_quanta q_res *
  page398_i32
#CELL
  pure_quanta q_res *
  page398_i33
#CELL
  pure_quanta q_cap *
  page398_i34
#CELL
  pure_quanta q_cap *
  page398_i35
#CELL
  pure_quanta q_cap *
  page398_i36
#ISCELL
  pure_quanta_power vcc_core *
  page398_i37
#CELL
  pure_quanta q_cap *
  page398_i39
#CELL
  pure_quanta q_cap *
  page398_i4
#CELL
  pure_quanta q_cap *
  page398_i40
#ISCELL
  pure_quanta_power universal_gnd *
  page398_i41
#CELL
  pure_quanta q_cap *
  page398_i42
#CELL
  pure_quanta q_cap *
  page398_i44
#CELL
  pure_quanta q_cap *
  page398_i46
#CELL
  pure_quanta q_cap *
  page398_i47
#CELL
  pure_quanta q_cap *
  page398_i48
#CELL
  pure_quanta q_cap *
  page398_i49
#CELL
  pure_quanta q_cap *
  page398_i5
#CELL
  pure_quanta q_cap *
  page398_i50
#CELL
  pure_quanta q_cap *
  page398_i51
#CELL
  pure_quanta q_cap *
  page398_i52
#CELL
  pure_quanta q_cap *
  page398_i53
#CELL
  pure_quanta q_cap *
  page398_i54
#CELL
  pure_quanta q_cap *
  page398_i55
#CELL
  pure_quanta q_cap *
  page398_i56
#CELL
  pure_quanta q_cap *
  page398_i57
#CELL
  pure_quanta q_cap *
  page398_i58
#CELL
  pure_quanta q_cap *
  page398_i59
#CELL
  pure_quanta q_cap *
  page398_i62
#CELL
  pure_quanta q_cap *
  page398_i63
#CELL
  pure_quanta q_cap *
  page398_i64
#CELL
  pure_quanta q_cap *
  page398_i65
#CELL
  pure_quanta q_cap *
  page398_i66
#CELL
  pure_quanta q_cap *
  page398_i67
#CELL
  pure_quanta q_cap *
  page398_i68
#ISCELL
  pure_quanta_power vcc_core *
  page398_i69
#CELL
  pure_quanta q_cap *
  page398_i7
#CELL
  pure_quanta q_cap *
  page398_i70
#CELL
  pure_quanta q_cap *
  page398_i71
#CELL
  pure_quanta q_cap *
  page398_i72
#CELL
  pure_quanta q_cap *
  page398_i73
#CELL
  pure_quanta q_inductor *
  page398_i74
#CELL
  pure_quanta q_cap *
  page398_i75
#CELL
  pure_quanta q_cap *
  page398_i76
#CELL
  pure_quanta q_cap *
  page398_i77
#CELL
  pure_quanta q_cap *
  page398_i78
#ISCELL
  pure_quanta_power universal_gnd *
  page398_i79
#CELL
  pure_quanta q_cap *
  page398_i80
#CELL
  pure_quanta q_cap *
  page398_i81
#CELL
  pure_quanta q_cap *
  page398_i82
#CELL
  pure_quanta q_cap *
  page398_i83
#CELL
  pure_quanta q_cap *
  page398_i84
#CELL
  pure_quanta q_cap *
  page398_i85
#CELL
  pure_quanta q_cap *
  page398_i86
#CELL
  pure_quanta q_cap *
  page398_i87
#ISCELL
  pure_quanta_power universal_gnd *
  page398_i88
#ISCELL
  pure_quanta_power vcc_core *
  page398_i89
#CELL
  pure_quanta q_cap *
  page398_i9
#ISCELL
  pure_quanta_power universal_gnd *
  page398_i91
#CELL
  pure_quanta q_cap *
  page398_i92
#CELL
  pure_quanta q_cap *
  page398_i93
#CELL
  pure_quanta q_res *
  page398_i95
#CELL
  pure_quanta q_res *
  page398_i96
#CELL
  pure_quanta q_inductor *
  page398_i97
#CELL
  pure_quanta q_res *
  page398_i98
#CELL
  pure_quanta q_cap *
  page398_i99
